(kicad_pcb
	(version 20260206)
	(generator "pcbnew")
	(generator_version "10.0")
	(general
		(thickness 1.6)
		(legacy_teardrops no)
	)
	(paper "A4")
	(title_block
		(title "03242023_DA0F0TMBIJ0_F0T_Motherboard_J_brd_V01_OCP.brd")
		(comment 1 "Grand Teton / footprints 2760-2767 of 6105")
	)
	(layers
		(0 "F.Cu" signal "TOP")
		(4 "In1.Cu" signal "GND")
		(6 "In2.Cu" signal "IN1")
		(8 "In3.Cu" signal "GND1")
		(10 "In4.Cu" signal "IN2")
		(12 "In5.Cu" signal "GND2")
		(14 "In6.Cu" signal "IN3")
		(16 "In7.Cu" signal "GND3")
		(18 "In8.Cu" signal "VCC")
		(20 "In9.Cu" signal "VCC1")
		(22 "In10.Cu" signal "GND4")
		(24 "In11.Cu" signal "IN4")
		(26 "In12.Cu" signal "GND5")
		(28 "In13.Cu" signal "IN5")
		(30 "In14.Cu" signal "GND6")
		(32 "In15.Cu" signal "IN6")
		(34 "In16.Cu" signal "GND7")
		(2 "B.Cu" signal "BOTTOM")
		(9 "F.Adhes" user "F.Adhesive")
		(11 "B.Adhes" user "B.Adhesive")
		(13 "F.Paste" user "Package Geometry/Pastemask Top")
		(15 "B.Paste" user "Package Geometry/Pastemask Bottom")
		(5 "F.SilkS" user "Ref Des/Silkscreen Top")
		(7 "B.SilkS" user "Ref Des/Silkscreen Bottom")
		(1 "F.Mask" user "Board Geometry/Soldermask Top")
		(3 "B.Mask" user "Board Geometry/Soldermask Bottom")
		(17 "Dwgs.User" user "User.Drawings")
		(19 "Cmts.User" user "User.Comments")
		(21 "Eco1.User" user "User.Eco1")
		(23 "Eco2.User" user "User.Eco2")
		(25 "Edge.Cuts" user "Board Geometry/Outline")
		(27 "Margin" user)
		(31 "F.CrtYd" user "Package Geometry/Place Bound Top")
		(29 "B.CrtYd" user "Package Geometry/Place Bound Bottom")
		(35 "F.Fab" user "Ref Des/Assembly Top")
		(33 "B.Fab" user "Ref Des/Assembly Bottom")
	)
	(footprint ""
		(layer "F.Cu")
		(at 230.248206 -246.693436 180)
		(property "Reference" "R3338"
			(at 0 0 180)
			(layer "F.SilkS")
			(hide yes)
			(effects
				(font
					(size 1.27 1.27)
				)
			)
		)
		(property "Value" ""
			(at 0 0 180)
			(layer "F.Fab")
			(effects
				(font
					(size 1.27 1.27)
				)
			)
		)
		(duplicate_pad_numbers_are_jumpers no)
		(fp_line
			(start 0.7874 0.4064)
			(end -0.7874 0.4064)
			(stroke
				(width 0.1524)
				(type default)
			)
			(layer "F.SilkS")
		)
		(fp_line
			(start 0.7874 -0.4064)
			(end 0.7874 0.4064)
			(stroke
				(width 0.1524)
				(type default)
			)
			(layer "F.SilkS")
		)
		(fp_line
			(start -0.7874 0.4064)
			(end -0.7874 -0.4064)
			(stroke
				(width 0.1524)
				(type default)
			)
			(layer "F.SilkS")
		)
		(fp_line
			(start -0.7874 -0.4064)
			(end 0.7874 -0.4064)
			(stroke
				(width 0.1524)
				(type default)
			)
			(layer "F.SilkS")
		)
		(fp_line
			(start 0.67945 0.3048)
			(end 0.120396 0.3048)
			(stroke
				(width 0.1)
				(type default)
			)
			(layer "F.Fab")
		)
		(fp_line
			(start 0.67945 -0.3048)
			(end 0.67945 0.3048)
			(stroke
				(width 0.1)
				(type default)
			)
			(layer "F.Fab")
		)
		(fp_line
			(start 0.12065 -0.2794)
			(end 0.12065 -0.3048)
			(stroke
				(width 0.1)
				(type default)
			)
			(layer "F.Fab")
		)
		(fp_line
			(start 0.12065 -0.3048)
			(end 0.67945 -0.3048)
			(stroke
				(width 0.1)
				(type default)
			)
			(layer "F.Fab")
		)
		(fp_line
			(start 0.120396 0.3048)
			(end 0.120396 0.2794)
			(stroke
				(width 0.1)
				(type default)
			)
			(layer "F.Fab")
		)
		(fp_line
			(start 0.120396 0.2794)
			(end -0.12065 0.2794)
			(stroke
				(width 0.1)
				(type default)
			)
			(layer "F.Fab")
		)
		(fp_line
			(start -0.12065 0.3048)
			(end -0.67945 0.3048)
			(stroke
				(width 0.1)
				(type default)
			)
			(layer "F.Fab")
		)
		(fp_line
			(start -0.12065 0.2794)
			(end -0.12065 0.3048)
			(stroke
				(width 0.1)
				(type default)
			)
			(layer "F.Fab")
		)
		(fp_line
			(start -0.12065 -0.2794)
			(end 0.12065 -0.2794)
			(stroke
				(width 0.1)
				(type default)
			)
			(layer "F.Fab")
		)
		(fp_line
			(start -0.12065 -0.305054)
			(end -0.12065 -0.2794)
			(stroke
				(width 0.1)
				(type default)
			)
			(layer "F.Fab")
		)
		(fp_line
			(start -0.67945 0.3048)
			(end -0.67945 -0.305054)
			(stroke
				(width 0.1)
				(type default)
			)
			(layer "F.Fab")
		)
		(fp_line
			(start -0.67945 -0.305054)
			(end -0.12065 -0.305054)
			(stroke
				(width 0.1)
				(type default)
			)
			(layer "F.Fab")
		)
		(pad "1" smd circle
			(at -0.40005 0 180)
			(size 0 0)
			(layers "F.Cu" "F.Mask" "F.Paste")
			(net "CLK_100M_GPU_FPGA_DN_R")
		)
		(pad "2" smd circle
			(at 0.40005 0 180)
			(size 0 0)
			(layers "F.Cu" "F.Mask" "F.Paste")
			(net "CLK_100M_GPU_FPGA_DN")
		)
	)
	(footprint ""
		(layer "F.Cu")
		(at 391.12317 -408.517344 -90)
		(property "Reference" "C882"
			(at 0 0 270)
			(layer "F.SilkS")
			(hide yes)
			(effects
				(font
					(size 1.27 1.27)
				)
			)
		)
		(property "Value" ""
			(at 0 0 270)
			(layer "F.Fab")
			(effects
				(font
					(size 1.27 1.27)
				)
			)
		)
		(duplicate_pad_numbers_are_jumpers no)
		(fp_line
			(start -0.299974 0.150114)
			(end -0.299974 -0.150114)
			(stroke
				(width 0.1)
				(type default)
			)
			(layer "F.Fab")
		)
		(fp_line
			(start 0.299974 0.150114)
			(end -0.299974 0.150114)
			(stroke
				(width 0.1)
				(type default)
			)
			(layer "F.Fab")
		)
		(fp_line
			(start -0.299974 -0.150114)
			(end 0.299974 -0.150114)
			(stroke
				(width 0.1)
				(type default)
			)
			(layer "F.Fab")
		)
		(fp_line
			(start 0.299974 -0.150114)
			(end 0.299974 0.150114)
			(stroke
				(width 0.1)
				(type default)
			)
			(layer "F.Fab")
		)
		(pad "1" smd rect
			(at -0.2667 0 270)
			(size 0.3048 0.381)
			(layers "F.Cu" "F.Mask" "F.Paste")
			(net "P5E_CPU0_PE3_TX_C_DN<9>")
		)
		(pad "2" smd rect
			(at 0.2667 0 270)
			(size 0.3048 0.381)
			(layers "F.Cu" "F.Mask" "F.Paste")
			(net "P5E_CPU0_PE3_TX_DN<9>")
		)
	)
	(footprint ""
		(layer "F.Cu")
		(at 105.39222 -296.05478 180)
		(property "Reference" "C250"
			(at 0 0 180)
			(layer "F.SilkS")
			(hide yes)
			(effects
				(font
					(size 1.27 1.27)
				)
			)
		)
		(property "Value" ""
			(at 0 0 180)
			(layer "F.Fab")
			(effects
				(font
					(size 1.27 1.27)
				)
			)
		)
		(duplicate_pad_numbers_are_jumpers no)
		(fp_line
			(start 1.524 0.762)
			(end -1.524 0.762)
			(stroke
				(width 0.1524)
				(type default)
			)
			(layer "F.SilkS")
		)
		(fp_line
			(start 1.524 -0.762)
			(end 1.524 0.762)
			(stroke
				(width 0.1524)
				(type default)
			)
			(layer "F.SilkS")
		)
		(fp_line
			(start -1.524 0.762)
			(end -1.524 -0.762)
			(stroke
				(width 0.1524)
				(type default)
			)
			(layer "F.SilkS")
		)
		(fp_line
			(start -1.524 -0.762)
			(end 1.524 -0.762)
			(stroke
				(width 0.1524)
				(type default)
			)
			(layer "F.SilkS")
		)
		(fp_line
			(start 1.1049 0.724916)
			(end 1.1049 -0.724916)
			(stroke
				(width 0.1)
				(type default)
			)
			(layer "F.Fab")
		)
		(fp_line
			(start 1.1049 -0.724916)
			(end -1.1049 -0.724916)
			(stroke
				(width 0.1)
				(type default)
			)
			(layer "F.Fab")
		)
		(fp_line
			(start -1.1049 0.724916)
			(end 1.1049 0.724916)
			(stroke
				(width 0.1)
				(type default)
			)
			(layer "F.Fab")
		)
		(fp_line
			(start -1.1049 -0.724916)
			(end -1.1049 0.724916)
			(stroke
				(width 0.1)
				(type default)
			)
			(layer "F.Fab")
		)
		(pad "1" smd rect
			(at -0.889 0)
			(size 1.016 1.27)
			(layers "F.Cu" "F.Mask" "F.Paste")
			(net "PVCCIN_CPU1")
		)
		(pad "2" smd rect
			(at 0.889 0)
			(size 1.016 1.27)
			(layers "F.Cu" "F.Mask" "F.Paste")
			(net "GND")
		)
	)
	(footprint ""
		(layer "F.Cu")
		(at 16.35506 -335.871312)
		(property "Reference" "U103"
			(at -5.4864 -3.969258 0)
			(unlocked yes)
			(layer "F.SilkS")
			(effects
				(font
					(size 0.7874 0.5842)
					(thickness 0.1524)
				)
				(justify left)
			)
		)
		(property "Value" ""
			(at 0 0 0)
			(layer "F.Fab")
			(effects
				(font
					(size 1.27 1.27)
				)
			)
		)
		(duplicate_pad_numbers_are_jumpers no)
		(fp_line
			(start -1.99263 -1.525016)
			(end -1.99263 1.525016)
			(stroke
				(width 0.1524)
				(type default)
			)
			(layer "F.SilkS")
		)
		(fp_line
			(start -1.99263 1.525016)
			(end 1.99263 1.525016)
			(stroke
				(width 0.1524)
				(type default)
			)
			(layer "F.SilkS")
		)
		(fp_line
			(start 1.99263 -1.525016)
			(end -1.99263 -1.525016)
			(stroke
				(width 0.1524)
				(type default)
			)
			(layer "F.SilkS")
		)
		(fp_line
			(start 1.99263 1.525016)
			(end 1.99263 -1.525016)
			(stroke
				(width 0.1524)
				(type default)
			)
			(layer "F.SilkS")
		)
		(fp_poly
			(pts
				(xy -4.286504 -1.43764) (xy -3.270504 -0.92964) (xy -4.286504 -0.42164)
			)
			(stroke
				(width 0)
				(type default)
			)
			(fill yes)
			(layer "F.SilkS")
		)
		(fp_line
			(start -0.87503 -1.525016)
			(end -0.87503 1.525016)
			(stroke
				(width 0.1)
				(type default)
			)
			(layer "F.Fab")
		)
		(fp_line
			(start -0.87503 1.525016)
			(end 0.87503 1.525016)
			(stroke
				(width 0.1)
				(type default)
			)
			(layer "F.Fab")
		)
		(fp_line
			(start 0.87503 -1.525016)
			(end -0.87503 -1.525016)
			(stroke
				(width 0.1)
				(type default)
			)
			(layer "F.Fab")
		)
		(fp_line
			(start 0.87503 1.525016)
			(end 0.87503 -1.525016)
			(stroke
				(width 0.1)
				(type default)
			)
			(layer "F.Fab")
		)
		(fp_poly
			(pts
				(xy -3.2004 -1.45796) (xy -3.2004 -0.44196) (xy -2.1844 -0.94996)
			)
			(stroke
				(width 0)
				(type default)
			)
			(fill yes)
			(layer "F.Fab")
		)
		(pad "1" smd circle
			(at -1.299972 -0.94996 270)
			(size 0 0)
			(layers "F.Cu" "F.Mask" "F.Paste")
			(net "GND")
		)
		(pad "2" smd circle
			(at -1.299972 0 270)
			(size 0 0)
			(layers "F.Cu" "F.Mask" "F.Paste")
			(net "GND")
		)
		(pad "3" smd circle
			(at -1.299972 0.94996 270)
			(size 0 0)
			(layers "F.Cu" "F.Mask" "F.Paste")
			(net "PVCCD_HV_CPU1_NVDIMM_ISENSE")
		)
		(pad "4" smd circle
			(at 1.299972 0.94996 270)
			(size 0 0)
			(layers "F.Cu" "F.Mask" "F.Paste")
			(net "P12V_AUX_CPU1_DIMM_ISEN_N")
		)
		(pad "5" smd circle
			(at 1.299972 -0.94996 270)
			(size 0 0)
			(layers "F.Cu" "F.Mask" "F.Paste")
			(net "P12V_AUX_CPU1_DIMM_ISEN_P")
		)
	)
	(footprint ""
		(layer "F.Cu")
		(at 93.582998 -47.049944 90)
		(property "Reference" "H74"
			(at -4.312666 -0.46101 0)
			(unlocked yes)
			(layer "F.SilkS")
			(effects
				(font
					(size 0.7874 0.5842)
					(thickness 0.1524)
				)
			)
		)
		(property "Value" ""
			(at 0 0 90)
			(layer "F.Fab")
			(effects
				(font
					(size 1.27 1.27)
				)
			)
		)
		(duplicate_pad_numbers_are_jumpers no)
		(pad "" np_thru_hole circle
			(at 0 0 90)
			(size 0 0)
			(drill oval 3.2004 4.8006)
			(layers "*.Cu" "*.Mask")
			(clearance -1.2192)
			(thermal_gap 0.381)
			(padstack
				(mode front_inner_back)
				(layer "Inner"
					(shape oval)
					(size 3.2004 4.8006)
					(clearance 0.381)
				)
				(layer "B.Cu"
					(shape circle)
					(size 0 0)
					(clearance -1.2192)
				)
			)
		)
		(zone
			(layers "F.Cu" "B.Cu" "In1.Cu" "In2.Cu" "In3.Cu" "In4.Cu" "In5.Cu" "In6.Cu"
				"In7.Cu" "In8.Cu" "In9.Cu" "In10.Cu" "In11.Cu" "In12.Cu" "In13.Cu" "In14.Cu"
				"In15.Cu" "In16.Cu"
			)
			(hatch none 0.5)
			(connect_pads
				(clearance 0)
			)
			(min_thickness 0.25)
			(keepout
				(tracks not_allowed)
				(vias allowed)
				(pads allowed)
				(copperpour not_allowed)
				(footprints allowed)
			)
			(placement
				(enabled no)
				(sheetname "")
			)
			(fill
				(thermal_gap 0.5)
				(thermal_bridge_width 0.5)
				(island_removal_mode 0)
			)
			(polygon
				(pts
					(arc
						(start 94.383098 -49.158144)
						(mid 96.491298 -47.049944)
						(end 94.383098 -44.941744)
					)
					(arc
						(start 92.782898 -44.941744)
						(mid 90.674698 -47.049944)
						(end 92.782898 -49.158144)
					)
				)
			)
		)
		(zone
			(layers "F.Cu" "B.Cu" "In1.Cu" "In2.Cu" "In3.Cu" "In4.Cu" "In5.Cu" "In6.Cu"
				"In7.Cu" "In8.Cu" "In9.Cu" "In10.Cu" "In11.Cu" "In12.Cu" "In13.Cu" "In14.Cu"
				"In15.Cu" "In16.Cu"
			)
			(hatch none 0.5)
			(connect_pads
				(clearance 0)
			)
			(min_thickness 0.25)
			(keepout
				(tracks not_allowed)
				(vias allowed)
				(pads allowed)
				(copperpour not_allowed)
				(footprints allowed)
			)
			(placement
				(enabled no)
				(sheetname "")
			)
			(fill
				(thermal_gap 0.5)
				(thermal_bridge_width 0.5)
				(island_removal_mode 0)
			)
			(polygon
				(pts
					(arc
						(start 94.383098 -50.050192)
						(mid 97.383346 -47.049944)
						(end 94.383098 -44.049696)
					)
					(arc
						(start 92.782898 -44.049696)
						(mid 89.78265 -47.049944)
						(end 92.782898 -50.050192)
					)
				)
			)
		)
	)
	(footprint ""
		(layer "F.Cu")
		(at 103.384096 -70.78599)
		(property "Reference" "D85"
			(at -51.698906 50.178462 90)
			(unlocked yes)
			(layer "F.SilkS")
			(effects
				(font
					(size 0.635 0.4064)
					(thickness 0.1524)
				)
				(justify left)
			)
		)
		(property "Value" ""
			(at 0 0 0)
			(layer "F.Fab")
			(effects
				(font
					(size 1.27 1.27)
				)
			)
		)
		(duplicate_pad_numbers_are_jumpers no)
		(fp_line
			(start -0.90678 0.4826)
			(end -0.90678 -0.4699)
			(stroke
				(width 0.1524)
				(type default)
			)
			(layer "F.SilkS")
		)
		(fp_line
			(start -0.89408 -0.4826)
			(end 0.90678 -0.4826)
			(stroke
				(width 0.1524)
				(type default)
			)
			(layer "F.SilkS")
		)
		(fp_line
			(start -0.79248 -0.4826)
			(end 1.03378 -0.4826)
			(stroke
				(width 0.1524)
				(type default)
			)
			(layer "F.SilkS")
		)
		(fp_line
			(start -0.64008 -0.4826)
			(end 1.16078 -0.4826)
			(stroke
				(width 0.1524)
				(type default)
			)
			(layer "F.SilkS")
		)
		(fp_line
			(start 0.90678 -0.4826)
			(end 0.90678 0.4826)
			(stroke
				(width 0.1524)
				(type default)
			)
			(layer "F.SilkS")
		)
		(fp_line
			(start 0.90678 0.4826)
			(end -0.90678 0.4826)
			(stroke
				(width 0.1524)
				(type default)
			)
			(layer "F.SilkS")
		)
		(fp_line
			(start 1.03378 -0.4826)
			(end 1.03378 0.4826)
			(stroke
				(width 0.1524)
				(type default)
			)
			(layer "F.SilkS")
		)
		(fp_line
			(start 1.03378 0.4826)
			(end -0.79248 0.4826)
			(stroke
				(width 0.1524)
				(type default)
			)
			(layer "F.SilkS")
		)
		(fp_line
			(start 1.16078 -0.4826)
			(end 1.16078 0.4826)
			(stroke
				(width 0.1524)
				(type default)
			)
			(layer "F.SilkS")
		)
		(fp_line
			(start 1.16078 0.4826)
			(end -0.64008 0.4826)
			(stroke
				(width 0.1524)
				(type default)
			)
			(layer "F.SilkS")
		)
		(fp_line
			(start -0.499872 -0.249936)
			(end 0.499872 -0.249936)
			(stroke
				(width 0.1)
				(type default)
			)
			(layer "F.Fab")
		)
		(fp_line
			(start -0.499872 0.249936)
			(end -0.499872 -0.249936)
			(stroke
				(width 0.1)
				(type default)
			)
			(layer "F.Fab")
		)
		(fp_line
			(start 0.499872 -0.249936)
			(end 0.499872 0.249936)
			(stroke
				(width 0.1)
				(type default)
			)
			(layer "F.Fab")
		)
		(fp_line
			(start 0.499872 0.249936)
			(end -0.499872 0.249936)
			(stroke
				(width 0.1)
				(type default)
			)
			(layer "F.Fab")
		)
		(pad "A" smd rect
			(at -0.47498 0)
			(size 0.6096 0.7112)
			(layers "F.Cu" "F.Mask" "F.Paste")
			(net "LED_PWRGD_PVNN_MAIN_CPU1")
		)
		(pad "C" smd rect
			(at 0.47498 0)
			(size 0.6096 0.7112)
			(layers "F.Cu" "F.Mask" "F.Paste")
			(net "LED_PWRGD_PVNN_MAIN_CPU1_D")
		)
	)
	(footprint ""
		(layer "F.Cu")
		(at 329.855068 -353.52482)
		(property "Reference" "H45"
			(at -3.64744 -5.138928 0)
			(unlocked yes)
			(layer "F.SilkS")
			(effects
				(font
					(size 0.7874 0.5842)
					(thickness 0.1524)
				)
				(justify left)
			)
		)
		(property "Value" ""
			(at 0 0 0)
			(layer "F.Fab")
			(effects
				(font
					(size 1.27 1.27)
				)
			)
		)
		(duplicate_pad_numbers_are_jumpers no)
		(pad "1" thru_hole circle
			(at 0 0)
			(size 8.001 8.001)
			(drill 3.2004)
			(layers "*.Cu" "*.Mask")
			(remove_unused_layers no)
			(net "GND")
			(clearance -2.1463)
			(padstack
				(mode front_inner_back)
				(layer "Inner"
					(shape circle)
					(size 5.0038 5.0038)
					(clearance -0.6477)
				)
				(layer "B.Cu"
					(shape circle)
					(size 8.001 8.001)
					(clearance -2.1463)
				)
			)
		)
	)
	(footprint ""
		(layer "F.Cu")
		(at 444.627 -76.164948 90)
		(property "Reference" "PC8"
			(at 0 0 90)
			(layer "F.SilkS")
			(hide yes)
			(effects
				(font
					(size 1.27 1.27)
				)
			)
		)
		(property "Value" ""
			(at 0 0 90)
			(layer "F.Fab")
			(effects
				(font
					(size 1.27 1.27)
				)
			)
		)
		(duplicate_pad_numbers_are_jumpers no)
		(fp_line
			(start 1.2954 -0.5842)
			(end 1.2954 0.5842)
			(stroke
				(width 0.1524)
				(type default)
			)
			(layer "F.SilkS")
		)
		(fp_line
			(start 0 -0.5842)
			(end 0 0.5842)
			(stroke
				(width 0.1524)
				(type default)
			)
			(layer "F.SilkS")
		)
		(fp_line
			(start -1.2954 -0.5842)
			(end 1.2954 -0.5842)
			(stroke
				(width 0.1524)
				(type default)
			)
			(layer "F.SilkS")
		)
		(fp_line
			(start 1.2954 0.5842)
			(end -1.2954 0.5842)
			(stroke
				(width 0.1524)
				(type default)
			)
			(layer "F.SilkS")
		)
		(fp_line
			(start -1.2954 0.5842)
			(end -1.2954 -0.5842)
			(stroke
				(width 0.1524)
				(type default)
			)
			(layer "F.SilkS")
		)
		(fp_line
			(start 0.8636 -0.4572)
			(end 0.8636 -0.4064)
			(stroke
				(width 0.1)
				(type default)
			)
			(layer "F.Fab")
		)
		(fp_line
			(start -0.8636 -0.4572)
			(end 0.8636 -0.4572)
			(stroke
				(width 0.1)
				(type default)
			)
			(layer "F.Fab")
		)
		(fp_line
			(start 1.1938 -0.4064)
			(end 1.1938 0.4064)
			(stroke
				(width 0.1)
				(type default)
			)
			(layer "F.Fab")
		)
		(fp_line
			(start 0.8636 -0.4064)
			(end 1.1938 -0.4064)
			(stroke
				(width 0.1)
				(type default)
			)
			(layer "F.Fab")
		)
		(fp_line
			(start -0.8636 -0.4064)
			(end -0.8636 -0.4572)
			(stroke
				(width 0.1)
				(type default)
			)
			(layer "F.Fab")
		)
		(fp_line
			(start -1.1938 -0.4064)
			(end -0.8636 -0.4064)
			(stroke
				(width 0.1)
				(type default)
			)
			(layer "F.Fab")
		)
		(fp_line
			(start 1.1938 0.4064)
			(end 0.8636 0.4064)
			(stroke
				(width 0.1)
				(type default)
			)
			(layer "F.Fab")
		)
		(fp_line
			(start 0.8636 0.4064)
			(end 0.8636 0.4572)
			(stroke
				(width 0.1)
				(type default)
			)
			(layer "F.Fab")
		)
		(fp_line
			(start -0.8636 0.4064)
			(end -1.1938 0.4064)
			(stroke
				(width 0.1)
				(type default)
			)
			(layer "F.Fab")
		)
		(fp_line
			(start -1.1938 0.4064)
			(end -1.1938 -0.4064)
			(stroke
				(width 0.1)
				(type default)
			)
			(layer "F.Fab")
		)
		(fp_line
			(start 0.8636 0.4572)
			(end -0.8636 0.4572)
			(stroke
				(width 0.1)
				(type default)
			)
			(layer "F.Fab")
		)
		(fp_line
			(start -0.8636 0.4572)
			(end -0.8636 0.4064)
			(stroke
				(width 0.1)
				(type default)
			)
			(layer "F.Fab")
		)
		(pad "1" smd rect
			(at -0.7366 0)
			(size 0.7112 0.8128)
			(layers "F.Cu" "F.Mask" "F.Paste")
			(net "P12V_AUX")
		)
		(pad "2" smd rect
			(at 0.7366 0)
			(size 0.7112 0.8128)
			(layers "F.Cu" "F.Mask" "F.Paste")
			(net "GND")
		)
	)
)
